(kicad_pcb
	(version 20260206)
	(generator "pcbnew")
	(generator_version "10.0")
	(general
		(thickness 1.6)
		(legacy_teardrops no)
	)
	(paper "A4")
	(title_block
		(title "01162023_DA0F0TEBIF0_F0T_Expander_BD_F_brd_V02_OCP.brd")
		(comment 1 "Grand Teton / footprints 9468-9475 of 9728")
	)
	(layers
		(0 "F.Cu" signal "TOP")
		(4 "In1.Cu" signal "GND")
		(6 "In2.Cu" signal "VCC")
		(8 "In3.Cu" signal "VCC1")
		(10 "In4.Cu" signal "GND1")
		(12 "In5.Cu" signal "IN1")
		(14 "In6.Cu" signal "GND2")
		(16 "In7.Cu" signal "IN2")
		(18 "In8.Cu" signal "GND3")
		(20 "In9.Cu" signal "IN3")
		(22 "In10.Cu" signal "GND4")
		(24 "In11.Cu" signal "IN4")
		(26 "In12.Cu" signal "GND5")
		(28 "In13.Cu" signal "IN5")
		(30 "In14.Cu" signal "GND6")
		(32 "In15.Cu" signal "IN6")
		(34 "In16.Cu" signal "GND7")
		(2 "B.Cu" signal "BOTTOM")
		(9 "F.Adhes" user "F.Adhesive")
		(11 "B.Adhes" user "B.Adhesive")
		(13 "F.Paste" user "Package Geometry/Pastemask Top")
		(15 "B.Paste" user "Package Geometry/Pastemask Bottom")
		(5 "F.SilkS" user "Ref Des/Silkscreen Top")
		(7 "B.SilkS" user "Ref Des/Silkscreen Bottom")
		(1 "F.Mask" user "Board Geometry/Soldermask Top")
		(3 "B.Mask" user "Board Geometry/Soldermask Bottom")
		(17 "Dwgs.User" user "User.Drawings")
		(19 "Cmts.User" user "User.Comments")
		(21 "Eco1.User" user "User.Eco1")
		(23 "Eco2.User" user "User.Eco2")
		(25 "Edge.Cuts" user "Board Geometry/Outline")
		(27 "Margin" user)
		(31 "F.CrtYd" user "Package Geometry/Place Bound Top")
		(29 "B.CrtYd" user "Package Geometry/Place Bound Bottom")
		(35 "F.Fab" user "Ref Des/Assembly Top")
		(33 "B.Fab" user "Ref Des/Assembly Bottom")
	)
	(footprint ""
		(layer "B.Cu")
		(at 396.0749 -298.00804 90)
		(property "Reference" "C3590"
			(at 0 0 90)
			(layer "B.SilkS")
			(hide yes)
			(effects
				(font
					(size 1.27 1.27)
				)
				(justify mirror)
			)
		)
		(property "Value" ""
			(at 0 0 90)
			(layer "B.Fab")
			(effects
				(font
					(size 1.27 1.27)
				)
				(justify mirror)
			)
		)
		(duplicate_pad_numbers_are_jumpers no)
		(fp_line
			(start 0.299974 -0.150114)
			(end -0.299974 -0.150114)
			(stroke
				(width 0.1)
				(type default)
			)
			(layer "B.Fab")
		)
		(fp_line
			(start -0.299974 -0.150114)
			(end -0.299974 0.150114)
			(stroke
				(width 0.1)
				(type default)
			)
			(layer "B.Fab")
		)
		(fp_line
			(start 0.299974 0.150114)
			(end 0.299974 -0.150114)
			(stroke
				(width 0.1)
				(type default)
			)
			(layer "B.Fab")
		)
		(fp_line
			(start -0.299974 0.150114)
			(end 0.299974 0.150114)
			(stroke
				(width 0.1)
				(type default)
			)
			(layer "B.Fab")
		)
		(pad "1" smd rect
			(at 0.2667 0 270)
			(size 0.3048 0.381)
			(layers "B.Cu" "B.Mask" "B.Paste")
			(net "SYSPLL_VDDA18_PEX3")
		)
		(pad "2" smd rect
			(at -0.2667 0 270)
			(size 0.3048 0.381)
			(layers "B.Cu" "B.Mask" "B.Paste")
			(net "GND")
		)
	)
	(footprint ""
		(layer "B.Cu")
		(at 174.325026 -293.99992 90)
		(property "Reference" "C1380"
			(at 0 0 90)
			(layer "B.SilkS")
			(hide yes)
			(effects
				(font
					(size 1.27 1.27)
				)
				(justify mirror)
			)
		)
		(property "Value" ""
			(at 0 0 90)
			(layer "B.Fab")
			(effects
				(font
					(size 1.27 1.27)
				)
				(justify mirror)
			)
		)
		(duplicate_pad_numbers_are_jumpers no)
		(fp_line
			(start 0.299974 -0.150114)
			(end -0.299974 -0.150114)
			(stroke
				(width 0.1)
				(type default)
			)
			(layer "B.Fab")
		)
		(fp_line
			(start -0.299974 -0.150114)
			(end -0.299974 0.150114)
			(stroke
				(width 0.1)
				(type default)
			)
			(layer "B.Fab")
		)
		(fp_line
			(start 0.299974 0.150114)
			(end 0.299974 -0.150114)
			(stroke
				(width 0.1)
				(type default)
			)
			(layer "B.Fab")
		)
		(fp_line
			(start -0.299974 0.150114)
			(end 0.299974 0.150114)
			(stroke
				(width 0.1)
				(type default)
			)
			(layer "B.Fab")
		)
		(pad "1" smd rect
			(at 0.2667 0 270)
			(size 0.3048 0.381)
			(layers "B.Cu" "B.Mask" "B.Paste")
			(net "P0V8_PEX1")
		)
		(pad "2" smd rect
			(at -0.2667 0 270)
			(size 0.3048 0.381)
			(layers "B.Cu" "B.Mask" "B.Paste")
			(net "GND")
		)
	)
	(footprint ""
		(layer "B.Cu")
		(at 298.499784 -290.199826 90)
		(property "Reference" "C1682"
			(at 0 0 90)
			(layer "B.SilkS")
			(hide yes)
			(effects
				(font
					(size 1.27 1.27)
				)
				(justify mirror)
			)
		)
		(property "Value" ""
			(at 0 0 90)
			(layer "B.Fab")
			(effects
				(font
					(size 1.27 1.27)
				)
				(justify mirror)
			)
		)
		(duplicate_pad_numbers_are_jumpers no)
		(fp_line
			(start 0.299974 -0.150114)
			(end -0.299974 -0.150114)
			(stroke
				(width 0.1)
				(type default)
			)
			(layer "B.Fab")
		)
		(fp_line
			(start -0.299974 -0.150114)
			(end -0.299974 0.150114)
			(stroke
				(width 0.1)
				(type default)
			)
			(layer "B.Fab")
		)
		(fp_line
			(start 0.299974 0.150114)
			(end 0.299974 -0.150114)
			(stroke
				(width 0.1)
				(type default)
			)
			(layer "B.Fab")
		)
		(fp_line
			(start -0.299974 0.150114)
			(end 0.299974 0.150114)
			(stroke
				(width 0.1)
				(type default)
			)
			(layer "B.Fab")
		)
		(pad "1" smd rect
			(at 0.2667 0 270)
			(size 0.3048 0.381)
			(layers "B.Cu" "B.Mask" "B.Paste")
			(net "P0V8_SERDES_VDDA_PEX2")
		)
		(pad "2" smd rect
			(at -0.2667 0 270)
			(size 0.3048 0.381)
			(layers "B.Cu" "B.Mask" "B.Paste")
			(net "GND")
		)
	)
	(footprint ""
		(layer "B.Cu")
		(at 5.470398 -384.554476 -90)
		(property "Reference" "C4462"
			(at 0 0 90)
			(layer "B.SilkS")
			(hide yes)
			(effects
				(font
					(size 1.27 1.27)
				)
				(justify mirror)
			)
		)
		(property "Value" ""
			(at 0 0 90)
			(layer "B.Fab")
			(effects
				(font
					(size 1.27 1.27)
				)
				(justify mirror)
			)
		)
		(duplicate_pad_numbers_are_jumpers no)
		(fp_line
			(start -0.7874 0.4064)
			(end 0.7874 0.4064)
			(stroke
				(width 0.1524)
				(type default)
			)
			(layer "B.SilkS")
		)
		(fp_line
			(start 0.7874 0.4064)
			(end 0.7874 -0.4064)
			(stroke
				(width 0.1524)
				(type default)
			)
			(layer "B.SilkS")
		)
		(fp_line
			(start -0.7874 -0.4064)
			(end -0.7874 0.4064)
			(stroke
				(width 0.1524)
				(type default)
			)
			(layer "B.SilkS")
		)
		(fp_line
			(start 0.7874 -0.4064)
			(end -0.7874 -0.4064)
			(stroke
				(width 0.1524)
				(type default)
			)
			(layer "B.SilkS")
		)
		(fp_line
			(start -0.67945 0.3048)
			(end -0.120396 0.3048)
			(stroke
				(width 0.1)
				(type default)
			)
			(layer "B.Fab")
		)
		(fp_line
			(start -0.120396 0.3048)
			(end -0.120396 0.2794)
			(stroke
				(width 0.1)
				(type default)
			)
			(layer "B.Fab")
		)
		(fp_line
			(start 0.12065 0.3048)
			(end 0.67945 0.3048)
			(stroke
				(width 0.1)
				(type default)
			)
			(layer "B.Fab")
		)
		(fp_line
			(start 0.67945 0.3048)
			(end 0.67945 -0.305054)
			(stroke
				(width 0.1)
				(type default)
			)
			(layer "B.Fab")
		)
		(fp_line
			(start -0.120396 0.2794)
			(end 0.12065 0.2794)
			(stroke
				(width 0.1)
				(type default)
			)
			(layer "B.Fab")
		)
		(fp_line
			(start 0.12065 0.2794)
			(end 0.12065 0.3048)
			(stroke
				(width 0.1)
				(type default)
			)
			(layer "B.Fab")
		)
		(fp_line
			(start -0.12065 -0.2794)
			(end -0.12065 -0.3048)
			(stroke
				(width 0.1)
				(type default)
			)
			(layer "B.Fab")
		)
		(fp_line
			(start 0.12065 -0.2794)
			(end -0.12065 -0.2794)
			(stroke
				(width 0.1)
				(type default)
			)
			(layer "B.Fab")
		)
		(fp_line
			(start -0.67945 -0.3048)
			(end -0.67945 0.3048)
			(stroke
				(width 0.1)
				(type default)
			)
			(layer "B.Fab")
		)
		(fp_line
			(start -0.12065 -0.3048)
			(end -0.67945 -0.3048)
			(stroke
				(width 0.1)
				(type default)
			)
			(layer "B.Fab")
		)
		(fp_line
			(start 0.12065 -0.305054)
			(end 0.12065 -0.2794)
			(stroke
				(width 0.1)
				(type default)
			)
			(layer "B.Fab")
		)
		(fp_line
			(start 0.67945 -0.305054)
			(end 0.12065 -0.305054)
			(stroke
				(width 0.1)
				(type default)
			)
			(layer "B.Fab")
		)
		(pad "1" smd circle
			(at 0.40005 0 90)
			(size 0 0)
			(layers "B.Cu" "B.Mask" "B.Paste")
			(net "P3V3_USB_8042")
		)
		(pad "2" smd circle
			(at -0.40005 0 90)
			(size 0 0)
			(layers "B.Cu" "B.Mask" "B.Paste")
			(net "GND")
		)
	)
	(footprint ""
		(layer "B.Cu")
		(at 377.725178 -225.092768 90)
		(property "Reference" "R6172"
			(at 0 0 90)
			(layer "B.SilkS")
			(hide yes)
			(effects
				(font
					(size 1.27 1.27)
				)
				(justify mirror)
			)
		)
		(property "Value" ""
			(at 0 0 90)
			(layer "B.Fab")
			(effects
				(font
					(size 1.27 1.27)
				)
				(justify mirror)
			)
		)
		(duplicate_pad_numbers_are_jumpers no)
		(fp_line
			(start 0.7874 -0.4064)
			(end -0.7874 -0.4064)
			(stroke
				(width 0.1524)
				(type default)
			)
			(layer "B.SilkS")
		)
		(fp_line
			(start -0.7874 -0.4064)
			(end -0.7874 0.4064)
			(stroke
				(width 0.1524)
				(type default)
			)
			(layer "B.SilkS")
		)
		(fp_line
			(start 0.7874 0.4064)
			(end 0.7874 -0.4064)
			(stroke
				(width 0.1524)
				(type default)
			)
			(layer "B.SilkS")
		)
		(fp_line
			(start -0.7874 0.4064)
			(end 0.7874 0.4064)
			(stroke
				(width 0.1524)
				(type default)
			)
			(layer "B.SilkS")
		)
		(fp_line
			(start 0.67945 -0.305054)
			(end 0.12065 -0.305054)
			(stroke
				(width 0.1)
				(type default)
			)
			(layer "B.Fab")
		)
		(fp_line
			(start 0.12065 -0.305054)
			(end 0.12065 -0.2794)
			(stroke
				(width 0.1)
				(type default)
			)
			(layer "B.Fab")
		)
		(fp_line
			(start -0.12065 -0.3048)
			(end -0.67945 -0.3048)
			(stroke
				(width 0.1)
				(type default)
			)
			(layer "B.Fab")
		)
		(fp_line
			(start -0.67945 -0.3048)
			(end -0.67945 0.3048)
			(stroke
				(width 0.1)
				(type default)
			)
			(layer "B.Fab")
		)
		(fp_line
			(start 0.12065 -0.2794)
			(end -0.12065 -0.2794)
			(stroke
				(width 0.1)
				(type default)
			)
			(layer "B.Fab")
		)
		(fp_line
			(start -0.12065 -0.2794)
			(end -0.12065 -0.3048)
			(stroke
				(width 0.1)
				(type default)
			)
			(layer "B.Fab")
		)
		(fp_line
			(start 0.12065 0.2794)
			(end 0.12065 0.3048)
			(stroke
				(width 0.1)
				(type default)
			)
			(layer "B.Fab")
		)
		(fp_line
			(start -0.120396 0.2794)
			(end 0.12065 0.2794)
			(stroke
				(width 0.1)
				(type default)
			)
			(layer "B.Fab")
		)
		(fp_line
			(start 0.67945 0.3048)
			(end 0.67945 -0.305054)
			(stroke
				(width 0.1)
				(type default)
			)
			(layer "B.Fab")
		)
		(fp_line
			(start 0.12065 0.3048)
			(end 0.67945 0.3048)
			(stroke
				(width 0.1)
				(type default)
			)
			(layer "B.Fab")
		)
		(fp_line
			(start -0.120396 0.3048)
			(end -0.120396 0.2794)
			(stroke
				(width 0.1)
				(type default)
			)
			(layer "B.Fab")
		)
		(fp_line
			(start -0.67945 0.3048)
			(end -0.120396 0.3048)
			(stroke
				(width 0.1)
				(type default)
			)
			(layer "B.Fab")
		)
		(pad "1" smd circle
			(at 0.40005 0 270)
			(size 0 0)
			(layers "B.Cu" "B.Mask" "B.Paste")
			(net "SPI_PEX3_RST_R_N")
		)
		(pad "2" smd circle
			(at -0.40005 0 270)
			(size 0 0)
			(layers "B.Cu" "B.Mask" "B.Paste")
			(net "P1V8_PEX")
		)
	)
	(footprint ""
		(layer "B.Cu")
		(at 53.630068 -295.221914)
		(property "Reference" "C1100"
			(at 0 0 0)
			(layer "B.SilkS")
			(hide yes)
			(effects
				(font
					(size 1.27 1.27)
				)
				(justify mirror)
			)
		)
		(property "Value" ""
			(at 0 0 0)
			(layer "B.Fab")
			(effects
				(font
					(size 1.27 1.27)
				)
				(justify mirror)
			)
		)
		(duplicate_pad_numbers_are_jumpers no)
		(fp_line
			(start -1.2954 -0.5842)
			(end -1.2954 0.5842)
			(stroke
				(width 0.1524)
				(type default)
			)
			(layer "B.SilkS")
		)
		(fp_line
			(start -1.2954 0.5842)
			(end 1.2954 0.5842)
			(stroke
				(width 0.1524)
				(type default)
			)
			(layer "B.SilkS")
		)
		(fp_line
			(start 1.2954 -0.5842)
			(end -1.2954 -0.5842)
			(stroke
				(width 0.1524)
				(type default)
			)
			(layer "B.SilkS")
		)
		(fp_line
			(start 1.2954 0.5842)
			(end 1.2954 -0.5842)
			(stroke
				(width 0.1524)
				(type default)
			)
			(layer "B.SilkS")
		)
		(fp_line
			(start -1.1938 -0.4064)
			(end -1.1938 0.4064)
			(stroke
				(width 0.1)
				(type default)
			)
			(layer "B.Fab")
		)
		(fp_line
			(start -1.1938 0.4064)
			(end -0.8636 0.4064)
			(stroke
				(width 0.1)
				(type default)
			)
			(layer "B.Fab")
		)
		(fp_line
			(start -0.8636 -0.4572)
			(end -0.8636 -0.4064)
			(stroke
				(width 0.1)
				(type default)
			)
			(layer "B.Fab")
		)
		(fp_line
			(start -0.8636 -0.4064)
			(end -1.1938 -0.4064)
			(stroke
				(width 0.1)
				(type default)
			)
			(layer "B.Fab")
		)
		(fp_line
			(start -0.8636 0.4064)
			(end -0.8636 0.4572)
			(stroke
				(width 0.1)
				(type default)
			)
			(layer "B.Fab")
		)
		(fp_line
			(start -0.8636 0.4572)
			(end 0.8636 0.4572)
			(stroke
				(width 0.1)
				(type default)
			)
			(layer "B.Fab")
		)
		(fp_line
			(start 0.8636 -0.4572)
			(end -0.8636 -0.4572)
			(stroke
				(width 0.1)
				(type default)
			)
			(layer "B.Fab")
		)
		(fp_line
			(start 0.8636 -0.4064)
			(end 0.8636 -0.4572)
			(stroke
				(width 0.1)
				(type default)
			)
			(layer "B.Fab")
		)
		(fp_line
			(start 0.8636 0.4064)
			(end 1.1938 0.4064)
			(stroke
				(width 0.1)
				(type default)
			)
			(layer "B.Fab")
		)
		(fp_line
			(start 0.8636 0.4572)
			(end 0.8636 0.4064)
			(stroke
				(width 0.1)
				(type default)
			)
			(layer "B.Fab")
		)
		(fp_line
			(start 1.1938 -0.4064)
			(end 0.8636 -0.4064)
			(stroke
				(width 0.1)
				(type default)
			)
			(layer "B.Fab")
		)
		(fp_line
			(start 1.1938 0.4064)
			(end 1.1938 -0.4064)
			(stroke
				(width 0.1)
				(type default)
			)
			(layer "B.Fab")
		)
		(pad "1" smd rect
			(at 0.7366 0 270)
			(size 0.7112 0.8128)
			(layers "B.Cu" "B.Mask" "B.Paste")
			(net "P0V8_PEX0")
		)
		(pad "2" smd rect
			(at -0.7366 0 270)
			(size 0.7112 0.8128)
			(layers "B.Cu" "B.Mask" "B.Paste")
			(net "GND")
		)
	)
	(footprint ""
		(layer "B.Cu")
		(at 403.199854 -303.499774 -90)
		(property "Reference" "C3432"
			(at 0 0 90)
			(layer "B.SilkS")
			(hide yes)
			(effects
				(font
					(size 1.27 1.27)
				)
				(justify mirror)
			)
		)
		(property "Value" ""
			(at 0 0 90)
			(layer "B.Fab")
			(effects
				(font
					(size 1.27 1.27)
				)
				(justify mirror)
			)
		)
		(duplicate_pad_numbers_are_jumpers no)
		(fp_line
			(start -0.299974 0.150114)
			(end 0.299974 0.150114)
			(stroke
				(width 0.1)
				(type default)
			)
			(layer "B.Fab")
		)
		(fp_line
			(start 0.299974 0.150114)
			(end 0.299974 -0.150114)
			(stroke
				(width 0.1)
				(type default)
			)
			(layer "B.Fab")
		)
		(fp_line
			(start -0.299974 -0.150114)
			(end -0.299974 0.150114)
			(stroke
				(width 0.1)
				(type default)
			)
			(layer "B.Fab")
		)
		(fp_line
			(start 0.299974 -0.150114)
			(end -0.299974 -0.150114)
			(stroke
				(width 0.1)
				(type default)
			)
			(layer "B.Fab")
		)
		(pad "1" smd rect
			(at 0.2667 0 90)
			(size 0.3048 0.381)
			(layers "B.Cu" "B.Mask" "B.Paste")
			(net "P1V25_PEX3")
		)
		(pad "2" smd rect
			(at -0.2667 0 90)
			(size 0.3048 0.381)
			(layers "B.Cu" "B.Mask" "B.Paste")
			(net "GND")
		)
	)
	(footprint ""
		(layer "B.Cu")
		(at 234.667552 -217.104214 -90)
		(property "Reference" "C2021"
			(at 0 0 90)
			(layer "B.SilkS")
			(hide yes)
			(effects
				(font
					(size 1.27 1.27)
				)
				(justify mirror)
			)
		)
		(property "Value" ""
			(at 0 0 90)
			(layer "B.Fab")
			(effects
				(font
					(size 1.27 1.27)
				)
				(justify mirror)
			)
		)
		(duplicate_pad_numbers_are_jumpers no)
		(fp_line
			(start -0.69215 0.2921)
			(end 0.69215 0.2921)
			(stroke
				(width 0.1524)
				(type default)
			)
			(layer "B.SilkS")
		)
		(fp_line
			(start 0.69215 0.2921)
			(end 0.69215 -0.2921)
			(stroke
				(width 0.1524)
				(type default)
			)
			(layer "B.SilkS")
		)
		(fp_line
			(start -0.69215 -0.2921)
			(end -0.69215 0.2921)
			(stroke
				(width 0.1524)
				(type default)
			)
			(layer "B.SilkS")
		)
		(fp_line
			(start 0.69215 -0.2921)
			(end -0.69215 -0.2921)
			(stroke
				(width 0.1524)
				(type default)
			)
			(layer "B.SilkS")
		)
		(fp_line
			(start -0.51435 0.2794)
			(end 0.51435 0.2794)
			(stroke
				(width 0.1)
				(type default)
			)
			(layer "B.Fab")
		)
		(fp_line
			(start 0.51435 0.2794)
			(end 0.51435 -0.2794)
			(stroke
				(width 0.1)
				(type default)
			)
			(layer "B.Fab")
		)
		(fp_line
			(start -0.51435 -0.2794)
			(end -0.51435 0.2794)
			(stroke
				(width 0.1)
				(type default)
			)
			(layer "B.Fab")
		)
		(fp_line
			(start 0.51435 -0.2794)
			(end -0.51435 -0.2794)
			(stroke
				(width 0.1)
				(type default)
			)
			(layer "B.Fab")
		)
		(pad "1" smd circle
			(at 0.40005 0 90)
			(size 0 0)
			(layers "B.Cu" "B.Mask" "B.Paste")
			(net "P1V2_BIC_PLL")
		)
		(pad "2" smd circle
			(at -0.40005 0 90)
			(size 0 0)
			(layers "B.Cu" "B.Mask" "B.Paste")
			(net "GND")
		)
		(zone
			(layer "B.Cu")
			(hatch none 0.5)
			(connect_pads
				(clearance 0)
			)
			(min_thickness 0.25)
			(keepout
				(tracks not_allowed)
				(vias allowed)
				(pads allowed)
				(copperpour not_allowed)
				(footprints allowed)
			)
			(placement
				(enabled no)
				(sheetname "")
			)
			(fill
				(thermal_gap 0.5)
				(thermal_bridge_width 0.5)
				(island_removal_mode 0)
			)
			(polygon
				(pts
					(xy 234.579922 -216.913714) (xy 234.521756 -217.005154) (xy 234.521756 -217.204544) (xy 234.579922 -217.294714)
					(xy 234.755182 -217.294714) (xy 234.813602 -217.204544) (xy 234.813602 -217.005154) (xy 234.755436 -216.913714)
				)
			)
		)
	)
)
